FILE_TYPE = CONNECTIVITY;
{Allegro Design Entry HDL 16.6-p007 (v16-6-112F) 10/10/2012}
"PAGE_NUMBER" = 102;
0"NC";
1"GND\g";
2"GND\g";
3"P3V3_DB1200\g";
4"P3V3_DB1200\g";
5"P3V3_DB1200\g";
6"P3V3_DB1200\g";
7"GND\g";
8"P3V3_DB1200\g";
9"GND\g";
10"P3V3_DB1200\g";
11"GND\g";
12"GND\g";
13"P3V3\g";
14"P3V3\g";
15"FM_100M_N";
16"FM_HBW_BYPASS_LOWBW_N";
17"NC_DB1200ZL<2>";
18"NC_DB1200ZL<0>";
19"NC_DB1200ZL<1>";
20"CLK_100M_CPU1_RC_REFCLK1_R_DP";
21"CLK_100M_CPU1_RC_REFCLK1_R_DN";
22"CLK_100M_CPU1_RC_REFCLK0_R_DP";
23"CLK_100M_CPU1_RC_REFCLK0_R_DN";
24"CLK_100M_CPU1_PE_REFCLK_R_DP";
25"CLK_100M_CPU1_PE_REFCLK_R_DN";
26"CLK_100M_CPU1_BCLK2_R_DP";
27"CLK_100M_CPU1_BCLK2_R_DN";
28"CLK_100M_CPU1_BCLK1_R_DP";
29"CLK_100M_CPU1_BCLK1_R_DN";
30"CLK_100M_CPU1_BCLK0_R_DP";
31"CLK_100M_CPU1_BCLK0_R_DN";
32"CLK_100M_CPU0_RC_REFCLK1_R_DP";
33"CLK_100M_CPU0_RC_REFCLK1_R_DN";
34"CLK_100M_CPU0_RC_REFCLK0_R_DP";
35"CLK_100M_CPU0_RC_REFCLK0_R_DN";
36"CLK_100M_CPU0_PE_REFCLK_R_DP";
37"CLK_100M_CPU0_PE_REFCLK_R_DN";
38"CLK_100M_CPU0_BCLK2_R_DP";
39"CLK_100M_CPU0_BCLK2_R_DN";
40"CLK_100M_CPU0_BCLK1_R_DP";
41"CLK_100M_CPU0_BCLK1_R_DN";
42"CLK_100M_CPU0_BCLK0_R_DP";
43"CLK_100M_CPU0_BCLK0_R_DN";
44"FM_CPU0_MCP_CLK_EN_N";
45"FM_CPU1_MCP_CLK_EN_N";
46"FM_DB1200ZL_BCLKS_EN_N";
47"P3V3_DB1200_A"VOLTAGE"+3.3V";
48"SMB_HOST_STBY_LVC3_SDA_R2";
49"SMB_HOST_STBY_LVC3_SCL_R2";
50"SMB_HOST_STBY_LVC3_SDA";
51"SMB_HOST_STBY_LVC3_SCL";
52"FM_CPU1_MCP_CLK_EN_N";
53"FM_DB1200ZL_BCLKS_EN_N";
54"FM_CPU0_MCP_CLK_EN_N";
55"FM_DB1200_SMB_SA0";
56"FM_DB1200_SMB_SA1";
57"SMB_HOST_STBY_LVC3_SCL_R2";
58"SMB_HOST_STBY_LVC3_SDA_R2";
59"FM_HBW_BYPASS_LOWBW_N";
60"FM_100M_N";
61"CLK_100M_DB1200_DP";
62"CLK_100M_DB1200_DN";
63"FM_DB1200_PWRGD";
64"P3V3_DB1200_R"VOLTAGE"+3.3V";
65"FM_DB1200_SMB_SA1";
66"FM_DB1200_SMB_SA0";
%"NB3W1200L"
"1","(350,2975)","0","mstr_clock","I1";
;
CDS_SEC"1"
CDS_LMAN_SYM_OUTLINE"-600,1000,600,-1000"
CDS_LIB"mstr_clock"
PACK_TYPE"LCC"
BOM_COST"SYS_CLOCK"
SEC_TYPE"LCC"
SEC"1"
ROOM"DB1200ZL"
CDS_LOCATION"EU4D2"
PART_NUMBER"H13585-001"
LOCATION"EU4D2"
MATERIAL"IC";
"SCL"
$PN"13"57;
"100M_133M_N"
$PN"4"60;
"OE_2_N"
$PN"28"53;
"OE_1_N"
$PN"20"53;
"OE_0_N"
$PN"19"53;
"OE_3_N"
$PN"29"54;
"OE_4_N"
$PN"36"54;
"OE_5_N"
$PN"37"54;
"OE_6_N"
$PN"44"53;
"OE_7_N"
$PN"45"53;
"VDDIO<1>"
$PN"32"5;
"VDDIO<2>"
$PN"49"5;
"VDDIO<0>"
$PN"25"5;
"VDDIO<3>"
$PN"56"5;
"OE_8_N"
$PN"52"53;
"OE_11_N"
$PN"62"52;
"OE_10_N"
$PN"61"52;
"OE_9_N"
$PN"53"52;
"VDD<2>"
$PN"57"5;
"VDD<1>"
$PN"40"5;
"VDDR"
$PN"8"64;
"VDD<0>"
$PN"24"5;
"VDDA"
$PN"1"47;
"GND<2>"
$PN"33"12;
"GND<4>"
$PN"48"12;
"GND<3>"
$PN"41"12;
"GND<5>"
$PN"58"12;
"THPAD"
$PN"65"12;
"GND<0>"
$PN"7"12;
"GND<1>"
$PN"23"12;
"GNDA"
$PN"2"12;
"DIF_2N"
$PN"27"39;
"DIF_1P"
$PN"21"40;
"DIF_1N"
$PN"22"41;
"DIF_0P"
$PN"17"42;
"DIF_0N"
$PN"18"43;
"DIF_2P"
$PN"26"38;
"DIF_6N"
$PN"43"31;
"DIF_5P"
$PN"38"32;
"DIF_3P"
$PN"30"36;
"DIF_4P"
$PN"34"34;
"DIF_4N"
$PN"35"35;
"DIF_5N"
$PN"39"33;
"DIF_3N"
$PN"31"37;
"DIF_6P"
$PN"42"30;
"DIF_7N"
$PN"47"29;
"DIF_7P"
$PN"46"28;
"DIF_11N"
$PN"64"21;
"DIF_11P"
$PN"63"20;
"DIF_10N"
$PN"60"23;
"DIF_9P"
$PN"54"24;
"DIF_10P"
$PN"59"22;
"DIF_9N"
$PN"55"25;
"DIF_8P"
$PN"50"26;
"DIF_8N"
$PN"51"27;
"CLK_INN"
$PN"10"62;
"CLK_INP"
$PN"9"61;
"HBW_BYPASS_LOBW_N \B"
$PN"5"59;
"PWRGD_PWRDN_N \B"
$PN"6"63;
"SA_0"
$PN"11"55;
"SA_1"
$PN"14"56;
"SDA"
$PN"12"58;
"NC<0>"
$PN"3"18;
"NC<2>"
$PN"15"17;
"NC<1>"
$PN"16"19;
%"CAP"
"1","(1975,975)","0","mstr_discrete","I10";
;
CDS_SEC"1"
BOM_COST"SYS_CLOCK"
SEC_TYPE"0805"
SEC"1"
CDS_LOCATION"C3D22"
ROOM"DB1200ZL"
CDS_LIB"mstr_discrete"
LOCATION"C3D22"
PART_NUMBER"G10601-001"
VALUE"10UF"
TOLERANCE"10%"
PACK_TYPE"0805"
VOLTAGE"16V"
MATERIAL"X7R";
"A"
$PN"1"3;
"B"
$PN"2"1;
%"CAP_A"
"1","(2575,975)","0","dev_discrete","I11";
;
BOM_COST"SYS_CLOCK"
SEC"1"
SEC_TYPE"0402V"
ROOM"DB1200ZL"
CDS_SEC"1"
CDS_LOCATION"C6P4"
CDS_LIB"dev_discrete"
LOCATION"C6P4"
VALUE"0.1UF"
PART_NUMBER"A36096-030"
MATERIAL"X7R"
VOLTAGE"16V"
PACK_TYPE"0402V"
TOLERANCE"10%";
"B"
$PN"2"1;
"A"
$PN"1"3;
%"CAP_A"
"1","(2825,975)","0","dev_discrete","I12";
;
BOM_COST"SYS_CLOCK"
ROOM"DB1200ZL"
CDS_LOCATION"C6P6"
CDS_SEC"1"
SEC_TYPE"0402V"
SEC"1"
CDS_LIB"dev_discrete"
PART_NUMBER"A36096-030"
LOCATION"C6P6"
VALUE"0.1UF"
MATERIAL"X7R"
VOLTAGE"16V"
PACK_TYPE"0402V"
TOLERANCE"10%";
"B"
$PN"2"1;
"A"
$PN"1"3;
%"CAP_A"
"1","(3050,975)","0","dev_discrete","I13";
;
BOM_COST"SYS_CLOCK"
SEC_TYPE"0402V"
ROOM"DB1200ZL"
CDS_LOCATION"C6P10"
CDS_SEC"1"
SEC"1"
CDS_LIB"dev_discrete"
VALUE"0.1UF"
LOCATION"C6P10"
PART_NUMBER"A36096-030"
MATERIAL"X7R"
VOLTAGE"16V"
PACK_TYPE"0402V"
TOLERANCE"10%";
"B"
$PN"2"1;
"A"
$PN"1"3;
%"CAP_A"
"1","(3275,975)","0","dev_discrete","I14";
;
BOM_COST"SYS_CLOCK"
SEC"1"
SEC_TYPE"0402V"
ROOM"DB1200ZL"
CDS_SEC"1"
CDS_LOCATION"C6P5"
CDS_LIB"dev_discrete"
LOCATION"C6P5"
VALUE"0.1UF"
PART_NUMBER"A36096-030"
TOLERANCE"10%"
PACK_TYPE"0402V"
VOLTAGE"16V"
MATERIAL"X7R";
"B"
$PN"2"1;
"A"
$PN"1"3;
%"CAP_A"
"1","(3475,975)","0","dev_discrete","I15";
;
BOM_COST"SYS_CLOCK"
SEC"1"
SEC_TYPE"0402V"
ROOM"DB1200ZL"
CDS_SEC"1"
CDS_LOCATION"C6P12"
CDS_LIB"dev_discrete"
LOCATION"C6P12"
VALUE"0.1UF"
PART_NUMBER"A36096-030"
TOLERANCE"10%"
PACK_TYPE"0402V"
VOLTAGE"16V"
MATERIAL"X7R";
"B"
$PN"2"1;
"A"
$PN"1"3;
%"CAP_A"
"1","(3700,975)","0","dev_discrete","I16";
;
BOM_COST"SYS_CLOCK"
CDS_SEC"1"
SEC_TYPE"0402V"
SEC"1"
CDS_LOCATION"C6P11"
ROOM"DB1200ZL"
CDS_LIB"dev_discrete"
LOCATION"C6P11"
VALUE"0.1UF"
PART_NUMBER"A36096-030"
PACK_TYPE"0402V"
TOLERANCE"10%"
VOLTAGE"16V"
MATERIAL"X7R";
"B"
$PN"2"1;
"A"
$PN"1"3;
%"GND"
"1","(3700,625)","0","mstr_symbols","I17";
;
HDL_POWER"GND"
SIZE"1B"
VOLTAGE"0.0V"
CDS_LIB"mstr_symbols"
BODY_TYPE"PLUMBING"
ROOM"DB1200ZL"
BOM_COST"SYS_CLOCK";
"A\NAC"1;
%"CAP_A"
"1","(-1550,3975)","0","dev_discrete","I18";
;
ROOM"DB1200ZL"
BOM_COST"SYS_CLOCK"
CDS_SEC"1"
SEC_TYPE"0402V"
SEC"1"
CDS_LOCATION"C4D24"
CDS_LIB"dev_discrete"
LOCATION"C4D24"
PART_NUMBER"A36096-030"
VALUE"0.1UF"
TOLERANCE"10%"
PACK_TYPE"0402V"
VOLTAGE"16V"
MATERIAL"X7R";
"B"
$PN"2"2;
"A"
$PN"1"47;
%"CAP_A"
"1","(-1800,3975)","0","dev_discrete","I19";
;
BOM_COST"SYS_CLOCK"
CDS_SEC"1"
SEC_TYPE"0402V"
SEC"1"
ROOM"DB1200ZL"
CDS_LOCATION"C4D23"
CDS_LIB"dev_discrete"
LOCATION"C4D23"
PART_NUMBER"D97712-004"
VALUE"1.0UF"
VOLTAGE"6.3V"
TOLERANCE"10%"
MATERIAL"X6S"
PACK_TYPE"0402V";
"B"
$PN"2"2;
"A"
$PN"1"47;
%"RES"
"1","(-2425,4200)","0","mstr_discrete","I21";
;
CDS_SEC"1"
BOM_COST"SYS_CLOCK"
SEC_TYPE"0603"
SEC"1"
ROOM"DB1200ZL"
CDS_LIB"mstr_discrete"
CDS_LOCATION"R3D14"
PART_NUMBER"G22026-127"
TOLERANCE"1.0%"
LOCATION"R3D14"
VALUE"2.2"
PACK_TYPE"0603"
MATERIAL"CHIP"
WATTAGE"1/10W";
"B"
$PN"2"47;
"A"
$PN"1"4;
%"GND"
"1","(-1550,3625)","0","mstr_symbols","I22";
;
SIZE"1B"
CDS_LIB"mstr_symbols"
HDL_POWER"GND"
BOM_COST"SYS_CLOCK"
ROOM"DB1200ZL"
VOLTAGE"0.0V"
BODY_TYPE"PLUMBING";
"A\NAC"2;
%"VCC_CORE"
"1","(3700,1375)","0","mstr_symbols","I23";
;
CDS_LIB"mstr_symbols"
VOLTAGE"5"
HDL_POWER"P3V3_DB1200";
"A"3;
%"VCC_CORE"
"1","(-2800,4325)","0","mstr_symbols","I24";
;
CDS_LIB"mstr_symbols"
VOLTAGE"5"
HDL_POWER"P3V3_DB1200";
"A"4;
%"VCC_CORE"
"1","(-825,4000)","0","mstr_symbols","I25";
;
VOLTAGE"5"
CDS_LIB"mstr_symbols"
HDL_POWER"P3V3_DB1200";
"A"5;
%"RES"
"1","(-2825,3475)","0","mstr_discrete","I26";
;
CDS_SEC"1"
BOM_COST"SYS_CLOCK"
SEC_TYPE"0603"
SEC"1"
ROOM"DB1200ZL"
CDS_LIB"mstr_discrete"
CDS_LOCATION"R6P25"
PART_NUMBER"G22026-127"
LOCATION"R6P25"
TOLERANCE"1.0%"
MATERIAL"CHIP"
VALUE"2.2"
PACK_TYPE"0603"
WATTAGE"1/10W";
"B"
$PN"2"64;
"A"
$PN"1"6;
%"VCC_CORE"
"1","(-3125,3625)","0","mstr_symbols","I27";
;
VOLTAGE"5"
CDS_LIB"mstr_symbols"
HDL_POWER"P3V3_DB1200";
"A"6;
%"CAP_A"
"1","(-2325,3300)","0","dev_discrete","I28";
;
BOM_COST"SYS_CLOCK"
ROOM"DB1200ZL"
CDS_LOCATION"C4D22"
CDS_SEC"1"
SEC_TYPE"0402V"
SEC"1"
CDS_LIB"dev_discrete"
PART_NUMBER"A36096-030"
LOCATION"C4D22"
VALUE"0.1UF"
TOLERANCE"10%"
PACK_TYPE"0402V"
VOLTAGE"16V"
MATERIAL"X7R";
"B"
$PN"2"7;
"A"
$PN"1"64;
%"GND"
"1","(-2325,2975)","0","mstr_symbols","I29";
;
HDL_POWER"GND"
BOM_COST"SYS_CLOCK"
ROOM"DB1200ZL"
VOLTAGE"0.0V"
CDS_LIB"mstr_symbols"
SIZE"1B"
BODY_TYPE"PLUMBING";
"A\NAC"7;
%"CAP_A"
"1","(-2575,3300)","0","dev_discrete","I30";
;
BOM_COST"SYS_CLOCK"
CDS_LOCATION"C4D27"
CDS_SEC"1"
SEC_TYPE"0402V"
SEC"1"
ROOM"DB1200ZL"
CDS_LIB"dev_discrete"
PART_NUMBER"D97712-004"
LOCATION"C4D27"
VALUE"1.0UF"
TOLERANCE"10%"
PACK_TYPE"0402V"
VOLTAGE"6.3V"
MATERIAL"X6S";
"B"
$PN"2"7;
"A"
$PN"1"64;
%"RES"
"2","(-2850,2925)","0","mstr_discrete","I37";
;
CDS_SEC"1"
ROOM"DB1200ZL"
SEC"1"
SEC_TYPE"0402"
BOM_COST"SYS_CLOCK"
CDS_LOCATION"R4D38"
CDS_LIB"mstr_discrete"
LOCATION"R4D38"
PART_NUMBER"G21796-016"
MATERIAL"EMPTY"
VALUE"10.0K"
WATTAGE"1/16W"
TOLERANCE"1%"
PACK_TYPE"0402";
"A"
$PN"1"8;
"B"
$PN"2"65;
%"RES"
"2","(-3225,2925)","0","mstr_discrete","I38";
;
CDS_SEC"1"
ROOM"DB1200ZL"
SEC"1"
SEC_TYPE"0402"
BOM_COST"SYS_CLOCK"
CDS_LOCATION"R4D35"
CDS_LIB"mstr_discrete"
MATERIAL"EMPTY"
LOCATION"R4D35"
PART_NUMBER"G21796-016"
VALUE"10.0K"
PACK_TYPE"0402"
WATTAGE"1/16W"
TOLERANCE"1%";
"A"
$PN"1"8;
"B"
$PN"2"66;
%"VCC_CORE"
"1","(-3225,3225)","0","mstr_symbols","I43";
;
VOLTAGE"5"
CDS_LIB"mstr_symbols"
HDL_POWER"P3V3_DB1200";
"A"8;
%"GND"
"1","(-2850,2200)","0","mstr_symbols","I44";
;
SIZE"1B"
HDL_POWER"GND"
CDS_LIB"mstr_symbols"
VOLTAGE"0.0V"
BODY_TYPE"PLUMBING"
BOM_COST"SYS_CLOCK"
ROOM"DB1200ZL";
"A\NAC"9;
%"RES"
"2","(-2675,1500)","0","mstr_discrete","I45";
;
CDS_SEC"1"
SEC_TYPE"0402"
BOM_COST"SYS_CLOCK"
SEC"1"
CDS_LOCATION"R4D40"
ROOM"DB1200ZL"
CDS_LIB"mstr_discrete"
LOCATION"R4D40"
PART_NUMBER"G21796-072"
VALUE"4.75K"
PACK_TYPE"0402"
MATERIAL"CHIP"
WATTAGE"1/16W"
TOLERANCE"1%";
"A"
$PN"1"10;
"B"
$PN"2"15;
%"RES"
"2","(-2675,1100)","0","mstr_discrete","I46";
;
CDS_SEC"1"
ROOM"DB1200ZL"
SEC"1"
BOM_COST"SYS_CLOCK"
SEC_TYPE"0402"
CDS_LOCATION"R6P23"
CDS_LIB"mstr_discrete"
WATTAGE"1/16W"
MATERIAL"EMPTY"
LOCATION"R6P23"
VALUE"4.75K"
TOLERANCE"1%"
PART_NUMBER"G21796-072"
PACK_TYPE"0402";
"A"
$PN"1"15;
"B"
$PN"2"11;
%"RES"
"2","(-2925,1100)","2","mstr_discrete","I47";
;
CDS_SEC"1"
SEC_TYPE"0402"
BOM_COST"SYS_CLOCK"
SEC"1"
ROOM"DB1200ZL"
CDS_LIB"mstr_discrete"
CDS_LOCATION"R6P22"
TOLERANCE"1%"
MATERIAL"EMPTY"
LOCATION"R6P22"
PART_NUMBER"G21796-072"
VALUE"4.75K"
PACK_TYPE"0402"
WATTAGE"1/16W";
"A"
$PN"1"16;
"B"
$PN"2"11;
%"VCC_CORE"
"1","(-2925,1875)","0","mstr_symbols","I49";
;
VOLTAGE"5"
CDS_LIB"mstr_symbols"
HDL_POWER"P3V3_DB1200";
"A"10;
%"GND"
"1","(-2675,775)","0","mstr_symbols","I50";
;
HDL_POWER"GND"
CDS_LIB"mstr_symbols"
SIZE"1B"
VOLTAGE"0.0V"
BODY_TYPE"PLUMBING"
ROOM"DB1200ZL"
BOM_COST"SYS_CLOCK";
"A\NAC"11;
%"RES"
"2","(-2925,1500)","2","mstr_discrete","I53";
;
CDS_SEC"1"
BOM_COST"SYS_CLOCK"
SEC_TYPE"0402"
SEC"1"
CDS_LOCATION"R4D41"
ROOM"DB1200ZL"
CDS_LIB"mstr_discrete"
TOLERANCE"1%"
LOCATION"R4D41"
PART_NUMBER"G21796-072"
VALUE"4.75K"
PACK_TYPE"0402"
MATERIAL"CHIP"
WATTAGE"1/16W";
"A"
$PN"1"10;
"B"
$PN"2"16;
%"GND"
"1","(1425,1800)","0","mstr_symbols","I6";
;
HDL_POWER"GND"
CDS_LIB"mstr_symbols"
SIZE"1B"
VOLTAGE"0.0V"
BODY_TYPE"PLUMBING"
ROOM"DB1200ZL"
BOM_COST"SYS_CLOCK";
"A\NAC"12;
%"CAP_A"
"1","(2275,975)","0","dev_discrete","I79";
;
CDS_SEC"1"
BOM_COST"SYS_CLOCK"
CDS_LOCATION"C6P9"
SEC"1"
ROOM"DB1200ZL"
SEC_TYPE"0402V"
CDS_LIB"dev_discrete"
LOCATION"C6P9"
VALUE"0.1UF"
PART_NUMBER"A36096-030"
VOLTAGE"16V"
MATERIAL"X7R"
TOLERANCE"10%"
PACK_TYPE"0402V";
"B"
$PN"2"1;
"A"
$PN"1"3;
%"FERRITE"
"1","(1700,1200)","0","mstr_discrete","I8";
;
CDS_SEC"1"
ROOM"DB1200ZL"
SEC"1"
SEC_TYPE"SMLF"
BOM_COST"SYS_CLOCK"
CDS_LOCATION"FB6P1"
CDS_LIB"mstr_discrete"
PART_NUMBER"656554-043"
MATERIAL"FB"
LOCATION"FB6P1"
PACK_TYPE"SMLF"
VALUE"600";
"A"
$PN"1"13;
"B"
$PN"2"3;
%"RES"
"2","(-3225,2550)","0","mstr_discrete","I80";
;
CDS_SEC"1"
SEC_TYPE"0402"
ROOM"DB1200ZL"
CDS_LOCATION"R6P21"
SEC"1"
BOM_COST"SYS_CLOCK"
CDS_LIB"mstr_discrete"
LOCATION"R6P21"
PART_NUMBER"G21796-026"
VALUE"1.00K"
PACK_TYPE"0402"
MATERIAL"CHIP"
WATTAGE"1/16W"
TOLERANCE"1%";
"A"
$PN"1"66;
"B"
$PN"2"9;
%"RES"
"2","(-2850,2550)","0","mstr_discrete","I81";
;
CDS_SEC"1"
SEC_TYPE"0402"
BOM_COST"SYS_CLOCK"
SEC"1"
CDS_LOCATION"R6P20"
ROOM"DB1200ZL"
CDS_LIB"mstr_discrete"
PART_NUMBER"G21796-026"
LOCATION"R6P20"
VALUE"1.00K"
TOLERANCE"1%"
WATTAGE"1/16W"
PACK_TYPE"0402"
MATERIAL"CHIP";
"A"
$PN"1"65;
"B"
$PN"2"9;
%"RES"
"1","(-1350,4875)","0","mstr_discrete","I82";
;
BOM_COST"SYS_CLOCK"
ROOM"DB1200ZL"
CDS_LIB"mstr_discrete"
CDS_SEC"1"
$SEC"1"
CDS_LOCATION"R4D36"
MATERIAL"CHIP"
WATTAGE"1/16W"
PART_NUMBER"G21796-074"
PACK_TYPE"0402"
TOLERANCE"1%"
LOCATION"R4D36"
VALUE"33.2";
"B"
$PN"2"48;
"A"
$PN"1"50;
%"RES"
"1","(-1350,4725)","0","mstr_discrete","I87";
;
BOM_COST"SYS_CLOCK"
ROOM"DB1200ZL"
CDS_SEC"1"
$SEC"1"
CDS_LIB"mstr_discrete"
CDS_LOCATION"R4D37"
MATERIAL"CHIP"
WATTAGE"1/16W"
PART_NUMBER"G21796-074"
PACK_TYPE"0402"
TOLERANCE"1%"
VALUE"33.2"
LOCATION"R4D37";
"B"
$PN"2"49;
"A"
$PN"1"51;
%"P3V3"
"1","(1475,1350)","0","mstr_symbols","I9";
;
BODY_TYPE"PLUMBING"
CDS_LIB"mstr_symbols"
SIZE"1B"
VOLTAGE"3.3V"
HDL_POWER"P3V3";
"G\NAC"13;
%"RES"
"2","(-425,1150)","2","mstr_discrete","I91";
;
CDS_SEC"1"
CDS_LOCATION"R6P48"
SIGNAL_MODEL"DEFAULT_RESISTOR_47000OHM_2_1"
SEC_TYPE"0402"
BOM_COST"SYS_CLOCK"
SEC"1"
ROOM"DB1200ZL"
CDS_LIB"mstr_discrete"
LOCATION"R6P48"
PART_NUMBER"G21796-072"
VALUE"4.75K"
TOLERANCE"1%"
MATERIAL"CHIP"
WATTAGE"1/16W"
PACK_TYPE"0402";
"A"
$PN"1"14;
"B"
$PN"2"46;
%"RES"
"2","(-125,1150)","2","mstr_discrete","I93";
;
CDS_SEC"1"
CDS_LOCATION"R4D69"
BOM_COST"SYS_CLOCK"
SIGNAL_MODEL"DEFAULT_RESISTOR_47000OHM_2_1"
SEC_TYPE"0402"
SEC"1"
ROOM"DB1200ZL"
CDS_LIB"mstr_discrete"
TOLERANCE"1%"
LOCATION"R4D69"
PART_NUMBER"G21796-072"
VALUE"4.75K"
MATERIAL"CHIP"
WATTAGE"1/16W"
PACK_TYPE"0402";
"A"
$PN"1"14;
"B"
$PN"2"45;
%"RES"
"2","(200,1150)","2","mstr_discrete","I94";
;
CDS_SEC"1"
CDS_LOCATION"R4D70"
SIGNAL_MODEL"DEFAULT_RESISTOR_47000OHM_2_1"
BOM_COST"SYS_CLOCK"
SEC_TYPE"0402"
SEC"1"
ROOM"DB1200ZL"
CDS_LIB"mstr_discrete"
LOCATION"R4D70"
VALUE"4.75K"
WATTAGE"1/16W"
TOLERANCE"1%"
MATERIAL"CHIP"
PACK_TYPE"0402"
PART_NUMBER"G21796-072";
"A"
$PN"1"14;
"B"
$PN"2"44;
%"P3V3"
"1","(-425,1450)","0","mstr_symbols","I95";
;
SIZE"1B"
CDS_LIB"mstr_symbols"
VOLTAGE"3.3V"
BODY_TYPE"PLUMBING"
HDL_POWER"P3V3";
"G\NAC"14;
END.
